(kicad_pcb
	(version 20241229)
	(generator "pcbnew")
	(generator_version "9.0")
	(general
		(thickness 1.6)
		(legacy_teardrops no)
	)
	(paper "A4")
	(title_block
		(title "GMSL Deserializer")
		(date "2025-10-09")
		(rev "1.0.4")
		(company "Antmicro Ltd")
		(comment 1 "www.antmicro.com")
		(comment 9 "footprints 218-221 of 235")
	)
	(layers
		(0 "F.Cu" signal)
		(4 "In1.Cu" power)
		(6 "In2.Cu" power)
		(2 "B.Cu" signal)
		(9 "F.Adhes" user "F.Adhesive")
		(11 "B.Adhes" user "B.Adhesive")
		(13 "F.Paste" user)
		(15 "B.Paste" user)
		(5 "F.SilkS" user "F.Silkscreen")
		(7 "B.SilkS" user "B.Silkscreen")
		(1 "F.Mask" user)
		(3 "B.Mask" user)
		(17 "Dwgs.User" user "User.Drawings")
		(19 "Cmts.User" user "User.Comments")
		(21 "Eco1.User" user "User.Eco1")
		(23 "Eco2.User" user "User.Eco2")
		(25 "Edge.Cuts" user)
		(27 "Margin" user)
		(31 "F.CrtYd" user "F.Courtyard")
		(29 "B.CrtYd" user "B.Courtyard")
		(35 "F.Fab" user)
		(33 "B.Fab" user)
	)
	(footprint "antmicro-footprints:Spacer_Drill3.7mm_H6mm_9774060151R"
		(layer "B.Cu")
		(at 120.498 44.164 180)
		(descr "Spacer M=3 h=36mm fi=5.1mm")
		(property "Reference" "H3"
			(at 0 3.2 0)
			(layer "B.SilkS")
			(effects
				(font
					(size 0.7 0.7)
					(thickness 0.15)
				)
				(justify left bottom mirror)
			)
		)
		(property "Value" "Spacer_Drill3.7mm_H6mm_9774060151R"
			(at 0 -4 0)
			(layer "B.Fab")
			(effects
				(font
					(size 0.7 0.7)
					(thickness 0.15)
				)
				(justify left bottom mirror)
			)
		)
		(property "Datasheet" "https://www.we-online.com/components/products/datasheet/9774060151R.pdf"
			(at 0 0 180)
			(layer "F.Fab")
			(hide yes)
			(effects
				(font
					(size 1.27 1.27)
					(thickness 0.15)
				)
			)
		)
		(property "Description" "Spacer, SMT, Non Stop, Steel, Swage Round, 5.1 mm x 6 mm, M2.5 Thread, WA-SMSI Series"
			(at 0 0 180)
			(layer "F.Fab")
			(hide yes)
			(effects
				(font
					(size 1.27 1.27)
					(thickness 0.15)
				)
			)
		)
		(property "Author" "Antmicro"
			(at 240.996 88.328 0)
			(layer "B.Fab")
			(hide yes)
			(effects
				(font
					(size 1 1)
					(thickness 0.15)
				)
				(justify mirror)
			)
		)
		(property "License" "Apache-2.0"
			(at 240.996 88.328 0)
			(layer "B.Fab")
			(hide yes)
			(effects
				(font
					(size 1 1)
					(thickness 0.15)
				)
				(justify mirror)
			)
		)
		(property "MPN" "9774060151R"
			(at 240.996 88.328 0)
			(layer "B.Fab")
			(hide yes)
			(effects
				(font
					(size 1 1)
					(thickness 0.15)
				)
				(justify mirror)
			)
		)
		(property "Manufacturer" "Würth Elektronik"
			(at 240.996 88.328 0)
			(layer "B.Fab")
			(hide yes)
			(effects
				(font
					(size 1 1)
					(thickness 0.15)
				)
				(justify mirror)
			)
		)
		(sheetname "/")
		(sheetfile "gmsl-deserializer.kicad_sch")
		(solder_paste_margin_ratio -1)
		(attr smd)
		(fp_circle
			(center 0 0)
			(end 3.05 0)
			(stroke
				(width 0.05)
				(type solid)
			)
			(fill no)
			(layer "B.CrtYd")
		)
		(fp_circle
			(center 0 0)
			(end 2.6 0)
			(stroke
				(width 0.15)
				(type solid)
			)
			(fill no)
			(layer "B.Fab")
		)
		(pad "" smd custom
			(at -1.7 -1.7 90)
			(size 0.62 0.62)
			(layers "B.Paste")
			(thermal_bridge_angle 90)
			(options
				(clearance outline)
				(anchor circle)
			)
			(primitives
				(gr_arc
					(start 1.266786 0.24747)
					(mid 0.285453 -0.29439)
					(end -0.250195 -1.279127)
					(width 0.2)
				)
				(gr_arc
					(start 1.259603 0.339191)
					(mid 0.218448 -0.232561)
					(end -0.34334 -1.279127)
					(width 0.2)
				)
				(gr_arc
					(start 1.255279 0.431435)
					(mid 0.152481 -0.169693)
					(end -0.436309 -1.279127)
					(width 0.2)
				)
				(gr_arc
					(start 1.253811 0.524161)
					(mid 0.087542 -0.105784)
					(end -0.529126 -1.279127)
					(width 0.2)
				)
				(gr_arc
					(start 1.275473 0.621136)
					(mid 0.0309 -0.033527)
					(end -0.621807 -1.279127)
					(width 0.2)
				)
				(gr_arc
					(start 1.263664 0.711602)
					(mid -0.037759 0.026651)
					(end -0.71437 -1.279127)
					(width 0.2)
				)
				(gr_arc
					(start 1.253435 0.802342)
					(mid -0.105837 0.087395)
					(end -0.806826 -1.279127)
					(width 0.2)
				)
				(gr_arc
					(start 1.267475 0.897258)
					(mid -0.165236 0.156885)
					(end -0.899187 -1.279127)
					(width 0.2)
				)
				(gr_arc
					(start 1.270645 0.990112)
					(mid -0.228522 0.222449)
					(end -0.991463 -1.279127)
					(width 0.2)
				)
				(gr_arc
					(start 1.266278 1.081674)
					(mid -0.294507 0.285313)
					(end -1.083663 -1.279127)
					(width 0.2)
				)
				(gr_line
					(start 1.279127 0.250195)
					(end 1.279127 1.083663)
					(width 0.2)
				)
				(gr_line
					(start -0.250195 -1.279127)
					(end -1.083663 -1.279127)
					(width 0.2)
				)
			)
		)
		(pad "" smd custom
			(at -1.7 1.7 180)
			(size 0.62 0.62)
			(layers "B.Paste")
			(thermal_bridge_angle 90)
			(options
				(clearance outline)
				(anchor circle)
			)
			(primitives
				(gr_arc
					(start 1.266786 0.24747)
					(mid 0.285453 -0.29439)
					(end -0.250195 -1.279127)
					(width 0.2)
				)
				(gr_arc
					(start 1.259603 0.339191)
					(mid 0.218448 -0.232561)
					(end -0.34334 -1.279127)
					(width 0.2)
				)
				(gr_arc
					(start 1.255279 0.431435)
					(mid 0.152481 -0.169693)
					(end -0.436309 -1.279127)
					(width 0.2)
				)
				(gr_arc
					(start 1.253811 0.524161)
					(mid 0.087542 -0.105784)
					(end -0.529126 -1.279127)
					(width 0.2)
				)
				(gr_arc
					(start 1.275473 0.621136)
					(mid 0.0309 -0.033527)
					(end -0.621807 -1.279127)
					(width 0.2)
				)
				(gr_arc
					(start 1.263664 0.711602)
					(mid -0.037759 0.026651)
					(end -0.71437 -1.279127)
					(width 0.2)
				)
				(gr_arc
					(start 1.253435 0.802342)
					(mid -0.105837 0.087395)
					(end -0.806826 -1.279127)
					(width 0.2)
				)
				(gr_arc
					(start 1.267475 0.897258)
					(mid -0.165236 0.156885)
					(end -0.899187 -1.279127)
					(width 0.2)
				)
				(gr_arc
					(start 1.270645 0.990112)
					(mid -0.228522 0.222449)
					(end -0.991463 -1.279127)
					(width 0.2)
				)
				(gr_arc
					(start 1.266278 1.081674)
					(mid -0.294507 0.285313)
					(end -1.083663 -1.279127)
					(width 0.2)
				)
				(gr_line
					(start 1.279127 0.250195)
					(end 1.279127 1.083663)
					(width 0.2)
				)
				(gr_line
					(start -0.250195 -1.279127)
					(end -1.083663 -1.279127)
					(width 0.2)
				)
			)
		)
		(pad "" smd custom
			(at 1.7 -1.7)
			(size 0.62 0.62)
			(layers "B.Paste")
			(thermal_bridge_angle 90)
			(options
				(clearance outline)
				(anchor circle)
			)
			(primitives
				(gr_arc
					(start 1.266786 0.24747)
					(mid 0.285453 -0.29439)
					(end -0.250195 -1.279127)
					(width 0.2)
				)
				(gr_arc
					(start 1.259603 0.339191)
					(mid 0.218448 -0.232561)
					(end -0.34334 -1.279127)
					(width 0.2)
				)
				(gr_arc
					(start 1.255279 0.431435)
					(mid 0.152481 -0.169693)
					(end -0.436309 -1.279127)
					(width 0.2)
				)
				(gr_arc
					(start 1.253811 0.524161)
					(mid 0.087542 -0.105784)
					(end -0.529126 -1.279127)
					(width 0.2)
				)
				(gr_arc
					(start 1.275473 0.621136)
					(mid 0.0309 -0.033527)
					(end -0.621807 -1.279127)
					(width 0.2)
				)
				(gr_arc
					(start 1.263664 0.711602)
					(mid -0.037759 0.026651)
					(end -0.71437 -1.279127)
					(width 0.2)
				)
				(gr_arc
					(start 1.253435 0.802342)
					(mid -0.105837 0.087395)
					(end -0.806826 -1.279127)
					(width 0.2)
				)
				(gr_arc
					(start 1.267475 0.897258)
					(mid -0.165236 0.156885)
					(end -0.899187 -1.279127)
					(width 0.2)
				)
				(gr_arc
					(start 1.270645 0.990112)
					(mid -0.228522 0.222449)
					(end -0.991463 -1.279127)
					(width 0.2)
				)
				(gr_arc
					(start 1.266278 1.081674)
					(mid -0.294507 0.285313)
					(end -1.083663 -1.279127)
					(width 0.2)
				)
				(gr_line
					(start 1.279127 0.250195)
					(end 1.279127 1.083663)
					(width 0.2)
				)
				(gr_line
					(start -0.250195 -1.279127)
					(end -1.083663 -1.279127)
					(width 0.2)
				)
			)
		)
		(pad "" smd custom
			(at 1.7 1.7 270)
			(size 0.62 0.62)
			(layers "B.Paste")
			(thermal_bridge_angle 90)
			(options
				(clearance outline)
				(anchor circle)
			)
			(primitives
				(gr_arc
					(start 1.266786 0.24747)
					(mid 0.285453 -0.29439)
					(end -0.250195 -1.279127)
					(width 0.2)
				)
				(gr_arc
					(start 1.259603 0.339191)
					(mid 0.218448 -0.232561)
					(end -0.34334 -1.279127)
					(width 0.2)
				)
				(gr_arc
					(start 1.255279 0.431435)
					(mid 0.152481 -0.169693)
					(end -0.436309 -1.279127)
					(width 0.2)
				)
				(gr_arc
					(start 1.253811 0.524161)
					(mid 0.087542 -0.105784)
					(end -0.529126 -1.279127)
					(width 0.2)
				)
				(gr_arc
					(start 1.275473 0.621136)
					(mid 0.0309 -0.033527)
					(end -0.621807 -1.279127)
					(width 0.2)
				)
				(gr_arc
					(start 1.263664 0.711602)
					(mid -0.037759 0.026651)
					(end -0.71437 -1.279127)
					(width 0.2)
				)
				(gr_arc
					(start 1.253435 0.802342)
					(mid -0.105837 0.087395)
					(end -0.806826 -1.279127)
					(width 0.2)
				)
				(gr_arc
					(start 1.267475 0.897258)
					(mid -0.165236 0.156885)
					(end -0.899187 -1.279127)
					(width 0.2)
				)
				(gr_arc
					(start 1.270645 0.990112)
					(mid -0.228522 0.222449)
					(end -0.991463 -1.279127)
					(width 0.2)
				)
				(gr_arc
					(start 1.266278 1.081674)
					(mid -0.294507 0.285313)
					(end -1.083663 -1.279127)
					(width 0.2)
				)
				(gr_line
					(start 1.279127 0.250195)
					(end 1.279127 1.083663)
					(width 0.2)
				)
				(gr_line
					(start -0.250195 -1.279127)
					(end -1.083663 -1.279127)
					(width 0.2)
				)
			)
		)
		(pad "1" thru_hole circle
			(at 0 0 180)
			(size 6 6)
			(drill 3.7)
			(layers "*.Cu" "*.Mask")
			(remove_unused_layers no)
			(net 1 "GND")
			(pintype "passive")
		)
	)
	(footprint "antmicro-footprints:R_0402_1005Metric"
		(layer "B.Cu")
		(at 133.858 83.82 180)
		(descr "Resistor SMD 0402")
		(tags "resistor SMD 0402")
		(property "Reference" "R56"
			(at -1.016109 -1.229033 0)
			(layer "B.SilkS")
			(effects
				(font
					(size 0.7 0.7)
					(thickness 0.15)
				)
				(justify left bottom mirror)
			)
		)
		(property "Value" "R_0R_0402"
			(at -1.011843 -1.772047 0)
			(layer "B.Fab")
			(effects
				(font
					(size 0.7 0.7)
					(thickness 0.15)
				)
				(justify left bottom mirror)
			)
		)
		(property "Datasheet" "https://industrial.panasonic.com/cdbs/www-data/pdf/RDA0000/AOA0000C301.pdf"
			(at 0 0 180)
			(layer "F.Fab")
			(hide yes)
			(effects
				(font
					(size 1.27 1.27)
					(thickness 0.15)
				)
			)
		)
		(property "Description" "SMD Chip Resistor, Jumper, 0 ohm, 100 mW, 0402 [1005 Metric], Thick Film, General Purpose"
			(at 0 0 180)
			(layer "F.Fab")
			(hide yes)
			(effects
				(font
					(size 1.27 1.27)
					(thickness 0.15)
				)
			)
		)
		(property "Author" "Antmicro"
			(at 267.716 167.64 0)
			(layer "B.Fab")
			(hide yes)
			(effects
				(font
					(size 1 1)
					(thickness 0.15)
				)
				(justify mirror)
			)
		)
		(property "Current" "1A"
			(at 267.716 167.64 0)
			(layer "B.Fab")
			(hide yes)
			(effects
				(font
					(size 1 1)
					(thickness 0.15)
				)
				(justify mirror)
			)
		)
		(property "License" "Apache-2.0"
			(at 267.716 167.64 0)
			(layer "B.Fab")
			(hide yes)
			(effects
				(font
					(size 1 1)
					(thickness 0.15)
				)
				(justify mirror)
			)
		)
		(property "MPN" "ERJ2GE0R00X"
			(at 267.716 167.64 0)
			(layer "B.Fab")
			(hide yes)
			(effects
				(font
					(size 1 1)
					(thickness 0.15)
				)
				(justify mirror)
			)
		)
		(property "Manufacturer" "Panasonic"
			(at 267.716 167.64 0)
			(layer "B.Fab")
			(hide yes)
			(effects
				(font
					(size 1 1)
					(thickness 0.15)
				)
				(justify mirror)
			)
		)
		(property "Tolerance" ""
			(at 267.716 167.64 0)
			(layer "B.Fab")
			(hide yes)
			(effects
				(font
					(size 1 1)
					(thickness 0.15)
				)
				(justify mirror)
			)
		)
		(property "Val" "0R"
			(at 267.716 167.64 0)
			(layer "B.Fab")
			(hide yes)
			(effects
				(font
					(size 1 1)
					(thickness 0.15)
				)
				(justify mirror)
			)
		)
		(sheetname "/Deserializer/")
		(sheetfile "deserializer.kicad_sch")
		(attr smd)
		(fp_rect
			(start -0.925 0.47)
			(end 0.925 -0.47)
			(stroke
				(width 0.05)
				(type default)
			)
			(fill no)
			(layer "B.CrtYd")
		)
		(fp_rect
			(start -0.5 0.25)
			(end 0.5 -0.25)
			(stroke
				(width 0.15)
				(type solid)
			)
			(fill no)
			(layer "B.Fab")
		)
		(pad "1" smd roundrect
			(at -0.48 0 180)
			(size 0.59 0.64)
			(layers "B.Cu" "B.Mask" "B.Paste")
			(roundrect_rratio 0.25)
			(net 146 "VDDIO")
			(pintype "passive")
		)
		(pad "2" smd roundrect
			(at 0.48 0 180)
			(size 0.59 0.64)
			(layers "B.Cu" "B.Mask" "B.Paste")
			(roundrect_rratio 0.25)
			(net 3 "+1V8")
			(pintype "passive")
		)
	)
	(footprint "antmicro-footprints:C_0402_1005Metric"
		(layer "B.Cu")
		(at 154.432 81.788 135)
		(descr "Capacitor SMD 0402")
		(tags "capacitor SMD 0402")
		(property "Reference" "C49"
			(at -1.271378 0.052326 315)
			(unlocked yes)
			(layer "B.SilkS")
			(effects
				(font
					(size 0.7 0.7)
					(thickness 0.15)
				)
				(justify right bottom mirror)
			)
		)
		(property "Value" "C_10n_0402"
			(at -1.022927 -2.155213 135)
			(layer "B.Fab")
			(effects
				(font
					(size 0.7 0.7)
					(thickness 0.15)
				)
				(justify right bottom mirror)
			)
		)
		(property "Datasheet" "https://www.murata.com/products/productdetail?partno=GRM155R71H103KA88%23"
			(at 0 0 135)
			(layer "F.Fab")
			(hide yes)
			(effects
				(font
					(size 1.27 1.27)
					(thickness 0.15)
				)
			)
		)
		(property "Description" "SMD Multilayer Ceramic Capacitor, 10000 pF, 50 V, 0402 [1005 Metric], ± 10%, X7R, GRM Series"
			(at 0 0 135)
			(layer "F.Fab")
			(hide yes)
			(effects
				(font
					(size 1.27 1.27)
					(thickness 0.15)
				)
			)
		)
		(property "Author" "Antmicro"
			(at 321.464764 30.420935 0)
			(layer "B.Fab")
			(hide yes)
			(effects
				(font
					(size 1 1)
					(thickness 0.15)
				)
				(justify mirror)
			)
		)
		(property "Dielectric" "X7R"
			(at 321.464764 30.420935 0)
			(layer "B.Fab")
			(hide yes)
			(effects
				(font
					(size 1 1)
					(thickness 0.15)
				)
				(justify mirror)
			)
		)
		(property "License" "Apache-2.0"
			(at 321.464764 30.420935 0)
			(layer "B.Fab")
			(hide yes)
			(effects
				(font
					(size 1 1)
					(thickness 0.15)
				)
				(justify mirror)
			)
		)
		(property "MPN" "GRM155R71H103KA88D"
			(at 321.464764 30.420935 0)
			(layer "B.Fab")
			(hide yes)
			(effects
				(font
					(size 1 1)
					(thickness 0.15)
				)
				(justify mirror)
			)
		)
		(property "Manufacturer" "Murata"
			(at 321.464764 30.420935 0)
			(layer "B.Fab")
			(hide yes)
			(effects
				(font
					(size 1 1)
					(thickness 0.15)
				)
				(justify mirror)
			)
		)
		(property "Val" "10n"
			(at 321.464764 30.420935 0)
			(layer "B.Fab")
			(hide yes)
			(effects
				(font
					(size 1 1)
					(thickness 0.15)
				)
				(justify mirror)
			)
		)
		(property "Voltage" "50V"
			(at 321.464764 30.420935 0)
			(layer "B.Fab")
			(hide yes)
			(effects
				(font
					(size 1 1)
					(thickness 0.15)
				)
				(justify mirror)
			)
		)
		(sheetname "/Deserializer/")
		(sheetfile "deserializer.kicad_sch")
		(attr smd)
		(fp_poly
			(pts
				(xy -0.925 0.47) (xy 0.925 0.47) (xy 0.925 -0.47) (xy -0.925 -0.47)
			)
			(stroke
				(width 0.05)
				(type default)
			)
			(fill no)
			(layer "B.CrtYd")
		)
		(fp_line
			(start 0.504 -0.248)
			(end 0.504 0.25)
			(stroke
				(width 0.15)
				(type solid)
			)
			(layer "B.Fab")
		)
		(fp_line
			(start 0.504 0.25)
			(end -0.494 0.25)
			(stroke
				(width 0.15)
				(type solid)
			)
			(layer "B.Fab")
		)
		(fp_line
			(start -0.494 -0.248)
			(end 0.504 -0.248)
			(stroke
				(width 0.15)
				(type solid)
			)
			(layer "B.Fab")
		)
		(fp_line
			(start -0.494 0.25)
			(end -0.494 -0.248)
			(stroke
				(width 0.15)
				(type solid)
			)
			(layer "B.Fab")
		)
		(pad "1" smd roundrect
			(at -0.48 0 135)
			(size 0.59 0.64)
			(layers "B.Cu" "B.Mask" "B.Paste")
			(roundrect_rratio 0.25)
			(net 1 "GND")
			(pintype "passive")
		)
		(pad "2" smd roundrect
			(at 0.48 0 135)
			(size 0.59 0.64)
			(layers "B.Cu" "B.Mask" "B.Paste")
			(roundrect_rratio 0.25)
			(net 27 "/Deserializer/VDD")
			(pintype "passive")
		)
	)
	(footprint "antmicro-footprints:C_0402_1005Metric"
		(layer "B.Cu")
		(at 139.7 83.058 45)
		(descr "Capacitor SMD 0402")
		(tags "capacitor SMD 0402")
		(property "Reference" "C51"
			(at -3.788853 -0.017146 45)
			(layer "B.SilkS")
			(effects
				(font
					(size 0.7 0.7)
					(thickness 0.15)
				)
				(justify right bottom mirror)
			)
		)
		(property "Value" "C_10n_0402"
			(at -1.022927 -2.155213 45)
			(layer "B.Fab")
			(effects
				(font
					(size 0.7 0.7)
					(thickness 0.15)
				)
				(justify right bottom mirror)
			)
		)
		(property "Datasheet" "https://www.murata.com/products/productdetail?partno=GRM155R71H103KA88%23"
			(at 0 0 45)
			(layer "F.Fab")
			(hide yes)
			(effects
				(font
					(size 1.27 1.27)
					(thickness 0.15)
				)
			)
		)
		(property "Description" "SMD Multilayer Ceramic Capacitor, 10000 pF, 50 V, 0402 [1005 Metric], ± 10%, X7R, GRM Series"
			(at 0 0 45)
			(layer "F.Fab")
			(hide yes)
			(effects
				(font
					(size 1.27 1.27)
					(thickness 0.15)
				)
			)
		)
		(property "Author" "Antmicro"
			(at 99.648057 -74.455692 0)
			(layer "B.Fab")
			(hide yes)
			(effects
				(font
					(size 1 1)
					(thickness 0.15)
				)
				(justify mirror)
			)
		)
		(property "Dielectric" "X7R"
			(at 99.648057 -74.455692 0)
			(layer "B.Fab")
			(hide yes)
			(effects
				(font
					(size 1 1)
					(thickness 0.15)
				)
				(justify mirror)
			)
		)
		(property "License" "Apache-2.0"
			(at 99.648057 -74.455692 0)
			(layer "B.Fab")
			(hide yes)
			(effects
				(font
					(size 1 1)
					(thickness 0.15)
				)
				(justify mirror)
			)
		)
		(property "MPN" "GRM155R71H103KA88D"
			(at 99.648057 -74.455692 0)
			(layer "B.Fab")
			(hide yes)
			(effects
				(font
					(size 1 1)
					(thickness 0.15)
				)
				(justify mirror)
			)
		)
		(property "Manufacturer" "Murata"
			(at 99.648057 -74.455692 0)
			(layer "B.Fab")
			(hide yes)
			(effects
				(font
					(size 1 1)
					(thickness 0.15)
				)
				(justify mirror)
			)
		)
		(property "Val" "10n"
			(at 99.648057 -74.455692 0)
			(layer "B.Fab")
			(hide yes)
			(effects
				(font
					(size 1 1)
					(thickness 0.15)
				)
				(justify mirror)
			)
		)
		(property "Voltage" "50V"
			(at 99.648057 -74.455692 0)
			(layer "B.Fab")
			(hide yes)
			(effects
				(font
					(size 1 1)
					(thickness 0.15)
				)
				(justify mirror)
			)
		)
		(sheetname "/Deserializer/")
		(sheetfile "deserializer.kicad_sch")
		(attr smd)
		(fp_poly
			(pts
				(xy -0.925 0.47) (xy 0.925 0.47) (xy 0.925 -0.47) (xy -0.925 -0.47)
			)
			(stroke
				(width 0.05)
				(type default)
			)
			(fill no)
			(layer "B.CrtYd")
		)
		(fp_line
			(start -0.494 -0.248)
			(end 0.504 -0.248)
			(stroke
				(width 0.15)
				(type solid)
			)
			(layer "B.Fab")
		)
		(fp_line
			(start -0.494 0.25)
			(end -0.494 -0.248)
			(stroke
				(width 0.15)
				(type solid)
			)
			(layer "B.Fab")
		)
		(fp_line
			(start 0.504 -0.248)
			(end 0.504 0.25)
			(stroke
				(width 0.15)
				(type solid)
			)
			(layer "B.Fab")
		)
		(fp_line
			(start 0.504 0.25)
			(end -0.494 0.25)
			(stroke
				(width 0.15)
				(type solid)
			)
			(layer "B.Fab")
		)
		(pad "1" smd roundrect
			(at -0.48 0 45)
			(size 0.59 0.64)
			(layers "B.Cu" "B.Mask" "B.Paste")
			(roundrect_rratio 0.25)
			(net 1 "GND")
			(pintype "passive")
		)
		(pad "2" smd roundrect
			(at 0.48 0 45)
			(size 0.59 0.64)
			(layers "B.Cu" "B.Mask" "B.Paste")
			(roundrect_rratio 0.25)
			(net 29 "/Deserializer/VTERM")
			(pintype "passive")
		)
	)
)
